(kicad_pcb
	(version 20241229)
	(generator "pcbnew")
	(generator_version "9.0")
	(general
		(thickness 0.876)
		(legacy_teardrops no)
	)
	(paper "A4")
	(title_block
		(rev "1.2.2")
		(comment 9 "footprints 4-5 of 20")
	)
	(layers
		(0 "F.Cu" signal)
		(4 "In1.Cu" signal)
		(6 "In2.Cu" signal)
		(2 "B.Cu" signal)
		(9 "F.Adhes" user "F.Adhesive")
		(11 "B.Adhes" user "B.Adhesive")
		(13 "F.Paste" user)
		(15 "B.Paste" user)
		(5 "F.SilkS" user "F.Silkscreen")
		(7 "B.SilkS" user "B.Silkscreen")
		(1 "F.Mask" user)
		(3 "B.Mask" user)
		(17 "Dwgs.User" user "User.Drawings")
		(19 "Cmts.User" user "User.Comments")
		(21 "Eco1.User" user "User.Eco1")
		(23 "Eco2.User" user "User.Eco2")
		(25 "Edge.Cuts" user)
		(27 "Margin" user)
		(31 "F.CrtYd" user "F.Courtyard")
		(29 "B.CrtYd" user "B.Courtyard")
		(35 "F.Fab" user)
		(33 "B.Fab" user)
	)
	(footprint "antmicro-footprints:PCB-Edge_M.2_Key-M"
		(layer "B.Cu")
		(at 106.200059 98.36752 90)
		(property "Reference" "J2"
			(at -0.05 6.025 90)
			(layer "B.SilkS")
			(hide yes)
			(effects
				(font
					(size 0.7 0.7)
					(thickness 0.15)
				)
				(justify right bottom mirror)
			)
		)
		(property "Value" "PCB-Edge_M.2_Key-M"
			(at -0.075 -2.25 90)
			(layer "B.Fab")
			(effects
				(font
					(size 0.7 0.7)
					(thickness 0.15)
				)
				(justify right bottom mirror)
			)
		)
		(property "Datasheet" "https://www.amphenol-icc.com/media/wysiwyg/files/drawing/10130618.pdf"
			(at 0 0 90)
			(layer "F.Fab")
			(hide yes)
			(effects
				(font
					(size 1.27 1.27)
					(thickness 0.15)
				)
			)
		)
		(property "Description" "PCB Edge for M.2 key M"
			(at 0 0 90)
			(layer "F.Fab")
			(hide yes)
			(effects
				(font
					(size 1.27 1.27)
					(thickness 0.15)
				)
			)
		)
		(property "Author" "Antmicro"
			(at 204.567579 -7.832539 0)
			(layer "B.Fab")
			(hide yes)
			(effects
				(font
					(size 1 1)
					(thickness 0.15)
				)
				(justify mirror)
			)
		)
		(property "License" "Apache-2.0"
			(at 204.567579 -7.832539 0)
			(layer "B.Fab")
			(hide yes)
			(effects
				(font
					(size 1 1)
					(thickness 0.15)
				)
				(justify mirror)
			)
		)
		(property "Public" "False"
			(at 204.567579 -7.832539 0)
			(layer "B.Fab")
			(hide yes)
			(effects
				(font
					(size 1 1)
					(thickness 0.15)
				)
				(justify mirror)
			)
		)
		(sheetname "/")
		(sheetfile "m2-pcie-adapter.kicad_sch")
		(attr exclude_from_pos_files exclude_from_bom)
		(fp_rect
			(start -10.075 0)
			(end 9.775 4)
			(stroke
				(width 0.05)
				(type solid)
			)
			(fill no)
			(layer "B.CrtYd")
		)
		(fp_rect
			(start -11.15 5.2)
			(end 10.85 0)
			(stroke
				(width 0.05)
				(type solid)
			)
			(fill no)
			(layer "F.CrtYd")
		)
		(pad "1" smd rect
			(at 9.1 1.45 90)
			(size 0.35 2.5)
			(layers "B.Cu" "B.Mask")
			(net 60 "GND")
			(pinfunction "GND")
			(pintype "passive")
		)
		(pad "2" smd rect
			(at 8.845243 1.7 90)
			(size 0.35 3)
			(layers "F.Cu" "F.Mask")
			(net 31 "/+3V3")
			(pinfunction "3.3V")
			(pintype "passive")
		)
		(pad "3" smd rect
			(at 8.6 1.45 90)
			(size 0.35 2.5)
			(layers "B.Cu" "B.Mask")
			(net 60 "GND")
			(pinfunction "GND")
			(pintype "passive")
		)
		(pad "4" smd rect
			(at 8.345243 1.7 90)
			(size 0.35 3)
			(layers "F.Cu" "F.Mask")
			(net 31 "/+3V3")
			(pinfunction "3.3V")
			(pintype "passive")
		)
		(pad "5" smd rect
			(at 8.1 1.45 90)
			(size 0.35 2.5)
			(layers "B.Cu" "B.Mask")
			(net 46 "/Data_3_IN_N")
			(pinfunction "PERn3")
			(pintype "passive")
		)
		(pad "6" smd rect
			(at 7.845243 1.7 90)
			(size 0.35 3)
			(layers "F.Cu" "F.Mask")
			(net 65 "unconnected-(J2-NC-Pad6)")
			(pinfunction "NC")
			(pintype "no_connect")
		)
		(pad "7" smd rect
			(at 7.6 1.45 90)
			(size 0.35 2.5)
			(layers "B.Cu" "B.Mask")
			(net 47 "/Data_3_IN_P")
			(pinfunction "PERp3")
			(pintype "passive")
		)
		(pad "8" smd rect
			(at 7.345243 1.7 90)
			(size 0.35 3)
			(layers "F.Cu" "F.Mask")
			(net 64 "unconnected-(J2-NC-Pad8)")
			(pinfunction "NC")
			(pintype "no_connect")
		)
		(pad "9" smd rect
			(at 7.1 1.45 90)
			(size 0.35 2.5)
			(layers "B.Cu" "B.Mask")
			(net 60 "GND")
			(pinfunction "GND")
			(pintype "passive")
		)
		(pad "10" smd rect
			(at 6.845243 1.7 90)
			(size 0.35 3)
			(layers "F.Cu" "F.Mask")
			(net 58 "unconnected-(J2-DAS-Pad10)")
			(pinfunction "DAS")
			(pintype "passive+no_connect")
		)
		(pad "11" smd rect
			(at 6.6 1.45 90)
			(size 0.35 2.5)
			(layers "B.Cu" "B.Mask")
			(net 49 "/Data_3_OUT_N")
			(pinfunction "PETn3")
			(pintype "passive")
		)
		(pad "12" smd rect
			(at 6.345243 1.7 90)
			(size 0.35 3)
			(layers "F.Cu" "F.Mask")
			(net 31 "/+3V3")
			(pinfunction "3.3V")
			(pintype "power_in")
		)
		(pad "13" smd rect
			(at 6.1 1.45 90)
			(size 0.35 2.5)
			(layers "B.Cu" "B.Mask")
			(net 48 "/Data_3_OUT_P")
			(pinfunction "PETp3")
			(pintype "passive")
		)
		(pad "14" smd rect
			(at 5.845243 1.7 90)
			(size 0.35 3)
			(layers "F.Cu" "F.Mask")
			(net 31 "/+3V3")
			(pinfunction "3.3V")
			(pintype "passive")
		)
		(pad "15" smd rect
			(at 5.6 1.45 90)
			(size 0.35 2.5)
			(layers "B.Cu" "B.Mask")
			(net 60 "GND")
			(pinfunction "GND")
			(pintype "passive")
		)
		(pad "16" smd rect
			(at 5.345243 1.7 90)
			(size 0.35 3)
			(layers "F.Cu" "F.Mask")
			(net 31 "/+3V3")
			(pinfunction "3.3V")
			(pintype "passive")
		)
		(pad "17" smd rect
			(at 5.1 1.45 90)
			(size 0.35 2.5)
			(layers "B.Cu" "B.Mask")
			(net 42 "/Data_2_IN_N")
			(pinfunction "PERn2")
			(pintype "passive")
		)
		(pad "18" smd rect
			(at 4.845243 1.7 90)
			(size 0.35 3)
			(layers "F.Cu" "F.Mask")
			(net 31 "/+3V3")
			(pinfunction "3.3V")
			(pintype "passive")
		)
		(pad "19" smd rect
			(at 4.6 1.45 90)
			(size 0.35 2.5)
			(layers "B.Cu" "B.Mask")
			(net 43 "/Data_2_IN_P")
			(pinfunction "PERp2")
			(pintype "passive")
		)
		(pad "20" smd rect
			(at 4.345243 1.7 90)
			(size 0.35 3)
			(layers "F.Cu" "F.Mask")
			(net 57 "unconnected-(J2-NC-Pad20)")
			(pinfunction "NC")
			(pintype "no_connect")
		)
		(pad "21" smd rect
			(at 4.1 1.45 90)
			(size 0.35 2.5)
			(layers "B.Cu" "B.Mask")
			(net 60 "GND")
			(pinfunction "GND")
			(pintype "passive")
		)
		(pad "22" smd rect
			(at 3.845243 1.7 90)
			(size 0.35 3)
			(layers "F.Cu" "F.Mask")
			(net 56 "unconnected-(J2-NC-Pad22)")
			(pinfunction "NC")
			(pintype "no_connect")
		)
		(pad "23" smd rect
			(at 3.6 1.45 90)
			(size 0.35 2.5)
			(layers "B.Cu" "B.Mask")
			(net 45 "/Data_2_OUT_N")
			(pinfunction "PETn2")
			(pintype "passive")
		)
		(pad "24" smd rect
			(at 3.345243 1.7 90)
			(size 0.35 3)
			(layers "F.Cu" "F.Mask")
			(net 55 "unconnected-(J2-NC-Pad24)")
			(pinfunction "NC")
			(pintype "no_connect")
		)
		(pad "25" smd rect
			(at 3.1 1.45 90)
			(size 0.35 2.5)
			(layers "B.Cu" "B.Mask")
			(net 44 "/Data_2_OUT_P")
			(pinfunction "PETp2")
			(pintype "passive")
		)
		(pad "26" smd rect
			(at 2.845243 1.7 90)
			(size 0.35 3)
			(layers "F.Cu" "F.Mask")
			(net 54 "unconnected-(J2-NC-Pad26)")
			(pinfunction "NC")
			(pintype "no_connect")
		)
		(pad "27" smd rect
			(at 2.6 1.45 90)
			(size 0.35 2.5)
			(layers "B.Cu" "B.Mask")
			(net 60 "GND")
			(pinfunction "GND")
			(pintype "passive")
		)
		(pad "28" smd rect
			(at 2.345243 1.7 90)
			(size 0.35 3)
			(layers "F.Cu" "F.Mask")
			(net 53 "unconnected-(J2-NC-Pad28)")
			(pinfunction "NC")
			(pintype "no_connect")
		)
		(pad "29" smd rect
			(at 2.1 1.45 90)
			(size 0.35 2.5)
			(layers "B.Cu" "B.Mask")
			(net 38 "/Data_1_IN_N")
			(pinfunction "PERn1")
			(pintype "passive")
		)
		(pad "30" smd rect
			(at 1.845243 1.7 90)
			(size 0.35 3)
			(layers "F.Cu" "F.Mask")
			(net 52 "unconnected-(J2-NC-Pad30)")
			(pinfunction "NC")
			(pintype "no_connect")
		)
		(pad "31" smd rect
			(at 1.6 1.45 90)
			(size 0.35 2.5)
			(layers "B.Cu" "B.Mask")
			(net 39 "/Data_1_IN_P")
			(pinfunction "PERp1")
			(pintype "passive")
		)
		(pad "32" smd rect
			(at 1.345243 1.7 90)
			(size 0.35 3)
			(layers "F.Cu" "F.Mask")
			(net 51 "unconnected-(J2-NC-Pad32)")
			(pinfunction "NC")
			(pintype "no_connect")
		)
		(pad "33" smd rect
			(at 1.1 1.45 90)
			(size 0.35 2.5)
			(layers "B.Cu" "B.Mask")
			(net 60 "GND")
			(pinfunction "GND")
			(pintype "passive")
		)
		(pad "34" smd rect
			(at 0.845243 1.7 90)
			(size 0.35 3)
			(layers "F.Cu" "F.Mask")
			(net 50 "unconnected-(J2-NC-Pad34)")
			(pinfunction "NC")
			(pintype "no_connect")
		)
		(pad "35" smd rect
			(at 0.6 1.45 90)
			(size 0.35 2.5)
			(layers "B.Cu" "B.Mask")
			(net 41 "/Data_1_OUT_N")
			(pinfunction "PETn1")
			(pintype "passive")
		)
		(pad "36" smd rect
			(at 0.345243 1.7 90)
			(size 0.35 3)
			(layers "F.Cu" "F.Mask")
			(net 29 "unconnected-(J2-NC-Pad36)")
			(pinfunction "NC")
			(pintype "no_connect")
		)
		(pad "37" smd rect
			(at 0.1 1.45 90)
			(size 0.35 2.5)
			(layers "B.Cu" "B.Mask")
			(net 40 "/Data_1_OUT_P")
			(pinfunction "PETp1")
			(pintype "passive")
		)
		(pad "38" smd rect
			(at -0.154757 1.7 90)
			(size 0.35 3)
			(layers "F.Cu" "F.Mask")
			(net 28 "unconnected-(J2-DEVSLP-Pad38)")
			(pinfunction "DEVSLP")
			(pintype "passive+no_connect")
		)
		(pad "39" smd rect
			(at -0.4 1.45 90)
			(size 0.35 2.5)
			(layers "B.Cu" "B.Mask")
			(net 60 "GND")
			(pinfunction "GND")
			(pintype "passive")
		)
		(pad "40" smd rect
			(at -0.654757 1.7 90)
			(size 0.35 3)
			(layers "F.Cu" "F.Mask")
			(net 27 "unconnected-(J2-NC-Pad40)")
			(pinfunction "NC")
			(pintype "no_connect")
		)
		(pad "41" smd rect
			(at -0.9 1.45 90)
			(size 0.35 2.5)
			(layers "B.Cu" "B.Mask")
			(net 34 "/Data_0_IN_N")
			(pinfunction "PERn0")
			(pintype "passive")
		)
		(pad "42" smd rect
			(at -1.154757 1.7 90)
			(size 0.35 3)
			(layers "F.Cu" "F.Mask")
			(net 26 "unconnected-(J2-NC-Pad42)")
			(pinfunction "NC")
			(pintype "no_connect")
		)
		(pad "43" smd rect
			(at -1.4 1.45 90)
			(size 0.35 2.5)
			(layers "B.Cu" "B.Mask")
			(net 35 "/Data_0_IN_P")
			(pinfunction "PERp0")
			(pintype "passive")
		)
		(pad "44" smd rect
			(at -1.654757 1.7 90)
			(size 0.35 3)
			(layers "F.Cu" "F.Mask")
			(net 25 "unconnected-(J2-NC-Pad44)")
			(pinfunction "NC")
			(pintype "no_connect")
		)
		(pad "45" smd rect
			(at -1.9 1.45 90)
			(size 0.35 2.5)
			(layers "B.Cu" "B.Mask")
			(net 60 "GND")
			(pinfunction "GND")
			(pintype "passive")
		)
		(pad "46" smd rect
			(at -2.154757 1.7 90)
			(size 0.35 3)
			(layers "F.Cu" "F.Mask")
			(net 24 "unconnected-(J2-NC-Pad46)")
			(pinfunction "NC")
			(pintype "no_connect")
		)
		(pad "47" smd rect
			(at -2.4 1.45 90)
			(size 0.35 2.5)
			(layers "B.Cu" "B.Mask")
			(net 37 "/Data_0_OUT_N")
			(pinfunction "PETn0")
			(pintype "passive")
		)
		(pad "48" smd rect
			(at -2.654757 1.7 90)
			(size 0.35 3)
			(layers "F.Cu" "F.Mask")
			(net 23 "unconnected-(J2-NC-Pad48)")
			(pinfunction "NC")
			(pintype "no_connect")
		)
		(pad "49" smd rect
			(at -2.9 1.45 90)
			(size 0.35 2.5)
			(layers "B.Cu" "B.Mask")
			(net 36 "/Data_0_OUT_P")
			(pinfunction "PETp0")
			(pintype "passive")
		)
		(pad "50" smd rect
			(at -3.154757 1.7 90)
			(size 0.35 3)
			(layers "F.Cu" "F.Mask")
			(net 59 "/PWRGD")
			(pinfunction "PERST#")
			(pintype "passive")
		)
		(pad "51" smd rect
			(at -3.4 1.45 90)
			(size 0.35 2.5)
			(layers "B.Cu" "B.Mask")
			(net 60 "GND")
			(pinfunction "GND")
			(pintype "passive")
		)
		(pad "52" smd rect
			(at -3.654757 1.7 90)
			(size 0.35 3)
			(layers "F.Cu" "F.Mask")
			(net 22 "Net-(J2-CLKREQ#)")
			(pinfunction "CLKREQ#")
			(pintype "passive")
		)
		(pad "53" smd rect
			(at -3.9 1.45 90)
			(size 0.35 2.5)
			(layers "B.Cu" "B.Mask")
			(net 33 "/REFCLK-")
			(pinfunction "REFCLKn")
			(pintype "passive")
		)
		(pad "54" smd rect
			(at -4.154757 1.7 90)
			(size 0.35 3)
			(layers "F.Cu" "F.Mask")
			(net 63 "/WAKE#")
			(pinfunction "PEWAKE#")
			(pintype "passive")
		)
		(pad "55" smd rect
			(at -4.4 1.45 90)
			(size 0.35 2.5)
			(layers "B.Cu" "B.Mask")
			(net 32 "/REFCLK+")
			(pinfunction "REFCLKp")
			(pintype "passive")
		)
		(pad "56" smd rect
			(at -4.654757 1.7 90)
			(size 0.35 3)
			(layers "F.Cu" "F.Mask")
			(net 21 "unconnected-(J2-NC-Pad56)")
			(pinfunction "NC")
			(pintype "no_connect")
		)
		(pad "57" smd rect
			(at -4.9 1.45 90)
			(size 0.35 2.5)
			(layers "B.Cu" "B.Mask")
			(net 60 "GND")
			(pinfunction "GND")
			(pintype "passive")
		)
		(pad "58" smd rect
			(at -5.154757 1.7 90)
			(size 0.35 3)
			(layers "F.Cu" "F.Mask")
			(net 20 "unconnected-(J2-NC-Pad58)")
			(pinfunction "NC")
			(pintype "no_connect")
		)
		(pad "67" smd rect
			(at -7.4 1.45 90)
			(size 0.35 2.5)
			(layers "B.Cu" "B.Mask")
			(net 19 "unconnected-(J2-NC-Pad67)")
			(pinfunction "NC")
			(pintype "no_connect")
		)
		(pad "68" smd rect
			(at -7.654757 1.7 90)
			(size 0.35 3)
			(layers "F.Cu" "F.Mask")
			(net 18 "unconnected-(J2-SUSCLK-Pad68)")
			(pinfunction "SUSCLK")
			(pintype "passive+no_connect")
		)
		(pad "69" smd rect
			(at -7.9 1.45 90)
			(size 0.35 2.5)
			(layers "B.Cu" "B.Mask")
			(net 17 "unconnected-(J2-PEDET-Pad69)")
			(pinfunction "PEDET")
			(pintype "passive+no_connect")
		)
		(pad "70" smd rect
			(at -8.154757 1.7 90)
			(size 0.35 3)
			(layers "F.Cu" "F.Mask")
			(net 31 "/+3V3")
			(pinfunction "3.3V")
			(pintype "passive")
		)
		(pad "71" smd rect
			(at -8.4 1.45 90)
			(size 0.35 2.5)
			(layers "B.Cu" "B.Mask")
			(net 60 "GND")
			(pinfunction "GND")
			(pintype "passive")
		)
		(pad "72" smd rect
			(at -8.654757 1.7 90)
			(size 0.35 3)
			(layers "F.Cu" "F.Mask")
			(net 31 "/+3V3")
			(pinfunction "3.3V")
			(pintype "passive")
		)
		(pad "73" smd rect
			(at -8.9 1.45 90)
			(size 0.35 2.5)
			(layers "B.Cu" "B.Mask")
			(net 60 "GND")
			(pinfunction "GND")
			(pintype "passive")
		)
		(pad "74" smd rect
			(at -9.154757 1.7 90)
			(size 0.35 3)
			(layers "F.Cu" "F.Mask")
			(net 31 "/+3V3")
			(pinfunction "3.3V")
			(pintype "passive")
		)
		(pad "75" smd rect
			(at -9.404757 1.45 90)
			(size 0.35 2.5)
			(layers "B.Cu" "B.Mask")
			(net 60 "GND")
			(pinfunction "GND")
			(pintype "passive")
		)
	)
	(footprint "antmicro-footprints:R_0402_1005Metric"
		(layer "B.Cu")
		(at 111.520059 104.427277 180)
		(descr "Resistor SMD 0402")
		(tags "resistor SMD 0402")
		(property "Reference" "R2"
			(at 0 -0.97 0)
			(layer "B.SilkS")
			(effects
				(font
					(size 0.7 0.7)
					(thickness 0.15)
				)
				(justify mirror)
			)
		)
		(property "Value" "R_0R_0402"
			(at 0 -1.17 0)
			(layer "B.Fab")
			(effects
				(font
					(size 1 1)
					(thickness 0.15)
				)
				(justify mirror)
			)
		)
		(property "Datasheet" "https://industrial.panasonic.com/cdbs/www-data/pdf/RDA0000/AOA0000C301.pdf"
			(at 0 0 180)
			(layer "F.Fab")
			(hide yes)
			(effects
				(font
					(size 1.27 1.27)
					(thickness 0.15)
				)
			)
		)
		(property "Description" "SMD Chip Resistor, Jumper, 0 ohm, 100 mW, 0402 [1005 Metric], Thick Film, General Purpose"
			(at 0 0 180)
			(layer "F.Fab")
			(hide yes)
			(effects
				(font
					(size 1.27 1.27)
					(thickness 0.15)
				)
			)
		)
		(property "Author" "Antmicro"
			(at 223.040118 208.854554 0)
			(layer "B.Fab")
			(hide yes)
			(effects
				(font
					(size 1 1)
					(thickness 0.15)
				)
				(justify mirror)
			)
		)
		(property "Current" "1A"
			(at 223.040118 208.854554 0)
			(layer "B.Fab")
			(hide yes)
			(effects
				(font
					(size 1 1)
					(thickness 0.15)
				)
				(justify mirror)
			)
		)
		(property "License" "Apache-2.0"
			(at 223.040118 208.854554 0)
			(layer "B.Fab")
			(hide yes)
			(effects
				(font
					(size 1 1)
					(thickness 0.15)
				)
				(justify mirror)
			)
		)
		(property "MPN" "ERJ2GE0R00X"
			(at 223.040118 208.854554 0)
			(layer "B.Fab")
			(hide yes)
			(effects
				(font
					(size 1 1)
					(thickness 0.15)
				)
				(justify mirror)
			)
		)
		(property "Manufacturer" "Panasonic"
			(at 223.040118 208.854554 0)
			(layer "B.Fab")
			(hide yes)
			(effects
				(font
					(size 1 1)
					(thickness 0.15)
				)
				(justify mirror)
			)
		)
		(property "Public" "False"
			(at 223.040118 208.854554 0)
			(layer "B.Fab")
			(hide yes)
			(effects
				(font
					(size 1 1)
					(thickness 0.15)
				)
				(justify mirror)
			)
		)
		(property "Tolerance" ""
			(at 223.040118 208.854554 0)
			(layer "B.Fab")
			(hide yes)
			(effects
				(font
					(size 1 1)
					(thickness 0.15)
				)
				(justify mirror)
			)
		)
		(property "Val" "0R"
			(at 223.040118 208.854554 0)
			(layer "B.Fab")
			(hide yes)
			(effects
				(font
					(size 1 1)
					(thickness 0.15)
				)
				(justify mirror)
			)
		)
		(sheetname "/")
		(sheetfile "m2-pcie-adapter.kicad_sch")
		(attr smd)
		(fp_rect
			(start -0.925 0.47)
			(end 0.925 -0.47)
			(stroke
				(width 0.05)
				(type default)
			)
			(fill no)
			(layer "B.CrtYd")
		)
		(fp_rect
			(start -0.5 0.25)
			(end 0.5 -0.25)
			(stroke
				(width 0.15)
				(type solid)
			)
			(fill no)
			(layer "B.Fab")
		)
		(fp_text user "${REFERENCE}"
			(at 0 0 0)
			(layer "B.Fab")
			(effects
				(font
					(size 0.25 0.25)
					(thickness 0.04)
				)
				(justify mirror)
			)
		)
		(pad "1" smd roundrect
			(at -0.48 0 180)
			(size 0.59 0.64)
			(layers "B.Cu" "B.Mask" "B.Paste")
			(roundrect_rratio 0.25)
			(net 22 "Net-(J2-CLKREQ#)")
			(pintype "passive")
		)
		(pad "2" smd roundrect
			(at 0.48 0 180)
			(size 0.59 0.64)
			(layers "B.Cu" "B.Mask" "B.Paste")
			(roundrect_rratio 0.25)
			(net 60 "GND")
			(pintype "passive")
		)
	)
)
